(kicad_pcb
	(version 20260206)
	(generator "pcbnew")
	(generator_version "10.0")
	(general
		(thickness 1.6)
		(legacy_teardrops no)
	)
	(paper "A4")
	(title_block
		(title "Wiwynn_Tioga_Pass_MB.brd")
		(comment 1 "Tioga Pass / footprint 190 of 4770 (U2D1), pads 2978-3045 of 3647")
	)
	(layers
		(0 "F.Cu" signal "TOP")
		(4 "In1.Cu" signal "L2GND")
		(6 "In2.Cu" signal "L3")
		(8 "In3.Cu" signal "L4GND")
		(10 "In4.Cu" signal "L5")
		(12 "In5.Cu" signal "L6GND")
		(14 "In6.Cu" signal "L7VCC")
		(16 "In7.Cu" signal "L8VCC")
		(18 "In8.Cu" signal "L9GND")
		(20 "In9.Cu" signal "L10")
		(22 "In10.Cu" signal "L11GND")
		(24 "In11.Cu" signal "L12")
		(26 "In12.Cu" signal "L13GND")
		(2 "B.Cu" signal "BOTTOM")
		(9 "F.Adhes" user "F.Adhesive")
		(11 "B.Adhes" user "B.Adhesive")
		(13 "F.Paste" user "Package Geometry/Pastemask Top")
		(15 "B.Paste" user "Package Geometry/Pastemask Bottom")
		(5 "F.SilkS" user "Ref Des/Silkscreen Top")
		(7 "B.SilkS" user "Ref Des/Silkscreen Bottom")
		(1 "F.Mask" user "Board Geometry/Soldermask Top")
		(3 "B.Mask" user "Board Geometry/Soldermask Bottom")
		(17 "Dwgs.User" user "User.Drawings")
		(19 "Cmts.User" user "User.Comments")
		(21 "Eco1.User" user "User.Eco1")
		(23 "Eco2.User" user "User.Eco2")
		(25 "Edge.Cuts" user "Board Geometry/Outline")
		(27 "Margin" user)
		(31 "F.CrtYd" user "Package Geometry/Place Bound Top")
		(29 "B.CrtYd" user "Package Geometry/Place Bound Bottom")
		(35 "F.Fab" user "Ref Des/Assembly Top")
		(33 "B.Fab" user "Ref Des/Assembly Bottom")
	)
	(footprint ""
		(layer "F.Cu")
		(at 104.99979 -76.550012 180)
		(property "Reference" "U2D1"
			(at 25.19299 30.484318 0)
			(unlocked yes)
			(layer "F.SilkS")
			(effects
				(font
					(size 0.7874 0.5842)
					(thickness 0.1524)
				)
			)
		)
		(property "Value" ""
			(at 0 0 180)
			(layer "F.Fab")
			(effects
				(font
					(size 1.27 1.27)
				)
			)
		)
		(duplicate_pad_numbers_are_jumpers no)
		(pad "EE44" smd custom
			(at 1.193546 24.608028 135)
			(size 0.10795 0.10795)
			(layers "F.Cu" "F.Mask" "F.Paste")
			(net "PVDDQ_KLM")
			(options
				(clearance outline)
				(anchor circle)
			)
			(primitives
				(gr_poly
					(pts
						(arc
							(start 0.2159 -0.0381)
							(mid 0 -0.254)
							(end -0.2159 -0.0381)
						)
						(arc
							(start -0.2159 0.0381)
							(mid 0 0.254)
							(end 0.2159 0.0381)
						)
					)
					(width 0)
					(fill yes)
				)
			)
		)
		(pad "EE46" smd circle
			(at 2.910586 24.608028)
			(size 0.4318 0.4318)
			(layers "F.Cu" "F.Mask" "F.Paste")
			(net "TP_CPU1_RSVD_7")
		)
		(pad "EE48" smd circle
			(at 4.627626 24.608028)
			(size 0.4318 0.4318)
			(layers "F.Cu" "F.Mask" "F.Paste")
			(net "M_K_ODT<1>")
		)
		(pad "EE50" smd circle
			(at 6.344412 24.608028)
			(size 0.4318 0.4318)
			(layers "F.Cu" "F.Mask" "F.Paste")
			(net "M_K_ODT<0>")
		)
		(pad "EE52" smd circle
			(at 8.061452 24.608028)
			(size 0.4318 0.4318)
			(layers "F.Cu" "F.Mask" "F.Paste")
			(net "M_K_BA<0>")
		)
		(pad "EE54" smd circle
			(at 9.778492 24.608028)
			(size 0.4318 0.4318)
			(layers "F.Cu" "F.Mask" "F.Paste")
			(net "M_K_CLK_DP<1>")
		)
		(pad "EE56" smd circle
			(at 11.495532 24.608028)
			(size 0.4318 0.4318)
			(layers "F.Cu" "F.Mask" "F.Paste")
			(net "M_K_CLK_DP<3>")
		)
		(pad "EE58" smd circle
			(at 13.212572 24.608028)
			(size 0.4318 0.4318)
			(layers "F.Cu" "F.Mask" "F.Paste")
			(net "M_K_MA<2>")
		)
		(pad "EE60" smd circle
			(at 14.929612 24.608028)
			(size 0.4318 0.4318)
			(layers "F.Cu" "F.Mask" "F.Paste")
			(net "M_K_MA<6>")
		)
		(pad "EE62" smd circle
			(at 16.646398 24.608028)
			(size 0.4318 0.4318)
			(layers "F.Cu" "F.Mask" "F.Paste")
			(net "M_K_CKE<0>")
		)
		(pad "EE70" smd custom
			(at 23.514558 24.608028 180)
			(size 0.10795 0.10795)
			(layers "F.Cu" "F.Mask" "F.Paste")
			(net "GND")
			(options
				(clearance outline)
				(anchor circle)
			)
			(primitives
				(gr_poly
					(pts
						(arc
							(start 0.2159 -0.0381)
							(mid 0 -0.254)
							(end -0.2159 -0.0381)
						)
						(arc
							(start -0.2159 0.0381)
							(mid 0 0.254)
							(end 0.2159 0.0381)
						)
					)
					(width 0)
					(fill yes)
				)
			)
		)
		(pad "EE72" smd circle
			(at 25.231598 24.608028)
			(size 0.4318 0.4318)
			(layers "F.Cu" "F.Mask" "F.Paste")
			(net "M_L_DQ<31>")
		)
		(pad "EE74" smd circle
			(at 26.948384 24.608028)
			(size 0.4318 0.4318)
			(layers "F.Cu" "F.Mask" "F.Paste")
			(net "M_L_DQ<25>")
		)
		(pad "EE76" smd circle
			(at 28.665424 24.608028)
			(size 0.4318 0.4318)
			(layers "F.Cu" "F.Mask" "F.Paste")
			(net "GND")
		)
		(pad "EE78" smd circle
			(at 30.382464 24.608028)
			(size 0.4318 0.4318)
			(layers "F.Cu" "F.Mask" "F.Paste")
			(net "GND")
		)
		(pad "EE80" smd custom
			(at 32.099504 24.608028 225)
			(size 0.10795 0.10795)
			(layers "F.Cu" "F.Mask" "F.Paste")
			(net "GND")
			(options
				(clearance outline)
				(anchor circle)
			)
			(primitives
				(gr_poly
					(pts
						(arc
							(start 0.2159 -0.0381)
							(mid 0 -0.254)
							(end -0.2159 -0.0381)
						)
						(arc
							(start -0.2159 0.0381)
							(mid 0 0.254)
							(end 0.2159 0.0381)
						)
					)
					(width 0)
					(fill yes)
				)
			)
		)
		(pad "EE82" smd custom
			(at 33.816544 24.608028 270)
			(size 0.10795 0.10795)
			(layers "F.Cu" "F.Mask" "F.Paste")
			(net "TP_CPU1_RSVD_5")
			(options
				(clearance outline)
				(anchor circle)
			)
			(primitives
				(gr_poly
					(pts
						(arc
							(start 0.2159 -0.0381)
							(mid 0 -0.254)
							(end -0.2159 -0.0381)
						)
						(arc
							(start -0.2159 0.0381)
							(mid 0 0.254)
							(end 0.2159 0.0381)
						)
					)
					(width 0)
					(fill yes)
				)
			)
		)
		(pad "EE84" smd custom
			(at 35.533584 24.608028 270)
			(size 0.10795 0.10795)
			(layers "F.Cu" "F.Mask" "F.Paste")
			(net "TP_CPU1_RSVD_4")
			(options
				(clearance outline)
				(anchor circle)
			)
			(primitives
				(gr_poly
					(pts
						(arc
							(start 0.2159 -0.0381)
							(mid 0 -0.254)
							(end -0.2159 -0.0381)
						)
						(arc
							(start -0.2159 0.0381)
							(mid 0 0.254)
							(end 0.2159 0.0381)
						)
					)
					(width 0)
					(fill yes)
				)
			)
		)
		(pad "EF45" smd custom
			(at 2.052066 25.103074 135)
			(size 0.10795 0.10795)
			(layers "F.Cu" "F.Mask" "F.Paste")
			(net "PVDDQ_KLM")
			(options
				(clearance outline)
				(anchor circle)
			)
			(primitives
				(gr_poly
					(pts
						(arc
							(start 0.2159 -0.0381)
							(mid 0 -0.254)
							(end -0.2159 -0.0381)
						)
						(arc
							(start -0.2159 0.0381)
							(mid 0 0.254)
							(end 0.2159 0.0381)
						)
					)
					(width 0)
					(fill yes)
				)
			)
		)
		(pad "EF47" smd custom
			(at 3.769106 25.103074 180)
			(size 0.10795 0.10795)
			(layers "F.Cu" "F.Mask" "F.Paste")
			(net "TP_CPU1_RSVD_3")
			(options
				(clearance outline)
				(anchor circle)
			)
			(primitives
				(gr_poly
					(pts
						(arc
							(start 0.2159 -0.0381)
							(mid 0 -0.254)
							(end -0.2159 -0.0381)
						)
						(arc
							(start -0.2159 0.0381)
							(mid 0 0.254)
							(end 0.2159 0.0381)
						)
					)
					(width 0)
					(fill yes)
				)
			)
		)
		(pad "EF49" smd custom
			(at 5.485892 25.103074 180)
			(size 0.10795 0.10795)
			(layers "F.Cu" "F.Mask" "F.Paste")
			(net "PVDDQ_KLM")
			(options
				(clearance outline)
				(anchor circle)
			)
			(primitives
				(gr_poly
					(pts
						(arc
							(start 0.2159 -0.0381)
							(mid 0 -0.254)
							(end -0.2159 -0.0381)
						)
						(arc
							(start -0.2159 0.0381)
							(mid 0 0.254)
							(end 0.2159 0.0381)
						)
					)
					(width 0)
					(fill yes)
				)
			)
		)
		(pad "EF51" smd custom
			(at 7.202932 25.103074 180)
			(size 0.10795 0.10795)
			(layers "F.Cu" "F.Mask" "F.Paste")
			(net "M_K_CS_N<0>")
			(options
				(clearance outline)
				(anchor circle)
			)
			(primitives
				(gr_poly
					(pts
						(arc
							(start 0.2159 -0.0381)
							(mid 0 -0.254)
							(end -0.2159 -0.0381)
						)
						(arc
							(start -0.2159 0.0381)
							(mid 0 0.254)
							(end 0.2159 0.0381)
						)
					)
					(width 0)
					(fill yes)
				)
			)
		)
		(pad "EF53" smd custom
			(at 8.919972 25.103074 180)
			(size 0.10795 0.10795)
			(layers "F.Cu" "F.Mask" "F.Paste")
			(net "PVDDQ_KLM")
			(options
				(clearance outline)
				(anchor circle)
			)
			(primitives
				(gr_poly
					(pts
						(arc
							(start 0.2159 -0.0381)
							(mid 0 -0.254)
							(end -0.2159 -0.0381)
						)
						(arc
							(start -0.2159 0.0381)
							(mid 0 0.254)
							(end 0.2159 0.0381)
						)
					)
					(width 0)
					(fill yes)
				)
			)
		)
		(pad "EF55" smd custom
			(at 10.637012 25.103074 180)
			(size 0.10795 0.10795)
			(layers "F.Cu" "F.Mask" "F.Paste")
			(net "M_K_CLK_DN<1>")
			(options
				(clearance outline)
				(anchor circle)
			)
			(primitives
				(gr_poly
					(pts
						(arc
							(start 0.2159 -0.0381)
							(mid 0 -0.254)
							(end -0.2159 -0.0381)
						)
						(arc
							(start -0.2159 0.0381)
							(mid 0 0.254)
							(end 0.2159 0.0381)
						)
					)
					(width 0)
					(fill yes)
				)
			)
		)
		(pad "EF57" smd custom
			(at 12.354052 25.103074 180)
			(size 0.10795 0.10795)
			(layers "F.Cu" "F.Mask" "F.Paste")
			(net "M_K_CLK_DN<3>")
			(options
				(clearance outline)
				(anchor circle)
			)
			(primitives
				(gr_poly
					(pts
						(arc
							(start 0.2159 -0.0381)
							(mid 0 -0.254)
							(end -0.2159 -0.0381)
						)
						(arc
							(start -0.2159 0.0381)
							(mid 0 0.254)
							(end 0.2159 0.0381)
						)
					)
					(width 0)
					(fill yes)
				)
			)
		)
		(pad "EF59" smd custom
			(at 14.071092 25.103074 180)
			(size 0.10795 0.10795)
			(layers "F.Cu" "F.Mask" "F.Paste")
			(net "PVDDQ_KLM")
			(options
				(clearance outline)
				(anchor circle)
			)
			(primitives
				(gr_poly
					(pts
						(arc
							(start 0.2159 -0.0381)
							(mid 0 -0.254)
							(end -0.2159 -0.0381)
						)
						(arc
							(start -0.2159 0.0381)
							(mid 0 0.254)
							(end 0.2159 0.0381)
						)
					)
					(width 0)
					(fill yes)
				)
			)
		)
		(pad "EF61" smd custom
			(at 15.787878 25.103074 180)
			(size 0.10795 0.10795)
			(layers "F.Cu" "F.Mask" "F.Paste")
			(net "M_K_MA<9>")
			(options
				(clearance outline)
				(anchor circle)
			)
			(primitives
				(gr_poly
					(pts
						(arc
							(start 0.2159 -0.0381)
							(mid 0 -0.254)
							(end -0.2159 -0.0381)
						)
						(arc
							(start -0.2159 0.0381)
							(mid 0 0.254)
							(end 0.2159 0.0381)
						)
					)
					(width 0)
					(fill yes)
				)
			)
		)
		(pad "EF63" smd custom
			(at 17.504918 25.103074 180)
			(size 0.10795 0.10795)
			(layers "F.Cu" "F.Mask" "F.Paste")
			(net "M_K_CKE<1>")
			(options
				(clearance outline)
				(anchor circle)
			)
			(primitives
				(gr_poly
					(pts
						(arc
							(start 0.2159 -0.0381)
							(mid 0 -0.254)
							(end -0.2159 -0.0381)
						)
						(arc
							(start -0.2159 0.0381)
							(mid 0 0.254)
							(end 0.2159 0.0381)
						)
					)
					(width 0)
					(fill yes)
				)
			)
		)
		(pad "EF71" smd custom
			(at 24.373078 25.103074 180)
			(size 0.10795 0.10795)
			(layers "F.Cu" "F.Mask" "F.Paste")
			(net "GND")
			(options
				(clearance outline)
				(anchor circle)
			)
			(primitives
				(gr_poly
					(pts
						(arc
							(start 0.2159 -0.0381)
							(mid 0 -0.254)
							(end -0.2159 -0.0381)
						)
						(arc
							(start -0.2159 0.0381)
							(mid 0 0.254)
							(end 0.2159 0.0381)
						)
					)
					(width 0)
					(fill yes)
				)
			)
		)
		(pad "EF73" smd custom
			(at 26.090118 25.103074 180)
			(size 0.10795 0.10795)
			(layers "F.Cu" "F.Mask" "F.Paste")
			(net "M_L_DQS_DN<3>")
			(options
				(clearance outline)
				(anchor circle)
			)
			(primitives
				(gr_poly
					(pts
						(arc
							(start 0.2159 -0.0381)
							(mid 0 -0.254)
							(end -0.2159 -0.0381)
						)
						(arc
							(start -0.2159 0.0381)
							(mid 0 0.254)
							(end 0.2159 0.0381)
						)
					)
					(width 0)
					(fill yes)
				)
			)
		)
		(pad "EF75" smd custom
			(at 27.806904 25.103074 180)
			(size 0.10795 0.10795)
			(layers "F.Cu" "F.Mask" "F.Paste")
			(net "GND")
			(options
				(clearance outline)
				(anchor circle)
			)
			(primitives
				(gr_poly
					(pts
						(arc
							(start 0.2159 -0.0381)
							(mid 0 -0.254)
							(end -0.2159 -0.0381)
						)
						(arc
							(start -0.2159 0.0381)
							(mid 0 0.254)
							(end 0.2159 0.0381)
						)
					)
					(width 0)
					(fill yes)
				)
			)
		)
		(pad "EF77" smd custom
			(at 29.523944 25.103074 180)
			(size 0.10795 0.10795)
			(layers "F.Cu" "F.Mask" "F.Paste")
			(net "TP_CPU1_RSVD_2")
			(options
				(clearance outline)
				(anchor circle)
			)
			(primitives
				(gr_poly
					(pts
						(arc
							(start 0.2159 -0.0381)
							(mid 0 -0.254)
							(end -0.2159 -0.0381)
						)
						(arc
							(start -0.2159 0.0381)
							(mid 0 0.254)
							(end 0.2159 0.0381)
						)
					)
					(width 0)
					(fill yes)
				)
			)
		)
		(pad "EF79" smd custom
			(at 31.240984 25.103074 180)
			(size 0.10795 0.10795)
			(layers "F.Cu" "F.Mask" "F.Paste")
			(net "GND")
			(options
				(clearance outline)
				(anchor circle)
			)
			(primitives
				(gr_poly
					(pts
						(arc
							(start 0.2159 -0.0381)
							(mid 0 -0.254)
							(end -0.2159 -0.0381)
						)
						(arc
							(start -0.2159 0.0381)
							(mid 0 0.254)
							(end 0.2159 0.0381)
						)
					)
					(width 0)
					(fill yes)
				)
			)
		)
		(pad "EF81" smd custom
			(at 32.958024 25.103074 225)
			(size 0.10795 0.10795)
			(layers "F.Cu" "F.Mask" "F.Paste")
			(net "TP_CPU1_RSVD_1")
			(options
				(clearance outline)
				(anchor circle)
			)
			(primitives
				(gr_poly
					(pts
						(arc
							(start 0.2159 -0.0381)
							(mid 0 -0.254)
							(end -0.2159 -0.0381)
						)
						(arc
							(start -0.2159 0.0381)
							(mid 0 0.254)
							(end 0.2159 0.0381)
						)
					)
					(width 0)
					(fill yes)
				)
			)
		)
		(pad "EF83" smd custom
			(at 34.675064 25.103074 225)
			(size 0.10795 0.10795)
			(layers "F.Cu" "F.Mask" "F.Paste")
			(net "TP_CPU1_RSVD_0")
			(options
				(clearance outline)
				(anchor circle)
			)
			(primitives
				(gr_poly
					(pts
						(arc
							(start 0.2159 -0.0381)
							(mid 0 -0.254)
							(end -0.2159 -0.0381)
						)
						(arc
							(start -0.2159 0.0381)
							(mid 0 0.254)
							(end 0.2159 0.0381)
						)
					)
					(width 0)
					(fill yes)
				)
			)
		)
		(pad "F3" smd custom
			(at -35.533584 -22.626828 45)
			(size 0.10795 0.10795)
			(layers "F.Cu" "F.Mask" "F.Paste")
			(net "TP_CPU1_RSVD_279")
			(options
				(clearance outline)
				(anchor circle)
			)
			(primitives
				(gr_poly
					(pts
						(arc
							(start 0.2159 -0.0381)
							(mid 0 -0.254)
							(end -0.2159 -0.0381)
						)
						(arc
							(start -0.2159 0.0381)
							(mid 0 0.254)
							(end 0.2159 0.0381)
						)
					)
					(width 0)
					(fill yes)
				)
			)
		)
		(pad "F5" smd circle
			(at -33.816544 -22.626828)
			(size 0.4318 0.4318)
			(layers "F.Cu" "F.Mask" "F.Paste")
			(net "GND")
		)
		(pad "F7" smd circle
			(at -32.099504 -22.626828)
			(size 0.4318 0.4318)
			(layers "F.Cu" "F.Mask" "F.Paste")
			(net "UPI_CPU1_CPU0_P1P1_DP<4>")
		)
		(pad "F9" smd circle
			(at -30.382464 -22.626828)
			(size 0.4318 0.4318)
			(layers "F.Cu" "F.Mask" "F.Paste")
			(net "UPI_CPU1_CPU0_P1P1_DN<7>")
		)
		(pad "F11" smd circle
			(at -28.665424 -22.626828)
			(size 0.4318 0.4318)
			(layers "F.Cu" "F.Mask" "F.Paste")
			(net "UPI_CPU1_CPU0_P1P1_DP<8>")
		)
		(pad "F13" smd circle
			(at -26.948384 -22.626828)
			(size 0.4318 0.4318)
			(layers "F.Cu" "F.Mask" "F.Paste")
			(net "UPI_CPU1_CPU0_P1P1_DN<11>")
		)
		(pad "F15" smd circle
			(at -25.231598 -22.626828)
			(size 0.4318 0.4318)
			(layers "F.Cu" "F.Mask" "F.Paste")
			(net "UPI_CPU1_CPU0_P1P1_DN<13>")
		)
		(pad "F17" smd circle
			(at -23.514558 -22.626828)
			(size 0.4318 0.4318)
			(layers "F.Cu" "F.Mask" "F.Paste")
			(net "GND")
		)
		(pad "F19" smd circle
			(at -21.797518 -22.626828)
			(size 0.4318 0.4318)
			(layers "F.Cu" "F.Mask" "F.Paste")
			(net "GND")
		)
		(pad "F21" smd circle
			(at -20.080478 -22.626828)
			(size 0.4318 0.4318)
			(layers "F.Cu" "F.Mask" "F.Paste")
			(net "UPI_CPU1_CPU0_P1P1_DP<18>")
		)
		(pad "F23" smd circle
			(at -18.363438 -22.626828)
			(size 0.4318 0.4318)
			(layers "F.Cu" "F.Mask" "F.Paste")
			(net "TP_CPU1_RSVD_278")
		)
		(pad "F25" smd circle
			(at -16.646398 -22.626828)
			(size 0.4318 0.4318)
			(layers "F.Cu" "F.Mask" "F.Paste")
			(net "GND")
		)
		(pad "F27" smd circle
			(at -14.929612 -22.626828)
			(size 0.4318 0.4318)
			(layers "F.Cu" "F.Mask" "F.Paste")
			(net "M_H_DQ<55>")
		)
		(pad "F29" smd circle
			(at -13.212572 -22.626828)
			(size 0.4318 0.4318)
			(layers "F.Cu" "F.Mask" "F.Paste")
			(net "M_H_DQ<53>")
		)
		(pad "F31" smd circle
			(at -11.495532 -22.626828)
			(size 0.4318 0.4318)
			(layers "F.Cu" "F.Mask" "F.Paste")
			(net "GND")
		)
		(pad "F33" smd circle
			(at -9.778492 -22.626828)
			(size 0.4318 0.4318)
			(layers "F.Cu" "F.Mask" "F.Paste")
			(net "M_H_DQ<47>")
		)
		(pad "F35" smd circle
			(at -8.061452 -22.626828)
			(size 0.4318 0.4318)
			(layers "F.Cu" "F.Mask" "F.Paste")
			(net "M_H_DQ<45>")
		)
		(pad "F37" smd circle
			(at -6.344412 -22.626828)
			(size 0.4318 0.4318)
			(layers "F.Cu" "F.Mask" "F.Paste")
			(net "GND")
		)
		(pad "F39" smd circle
			(at -4.627626 -22.626828)
			(size 0.4318 0.4318)
			(layers "F.Cu" "F.Mask" "F.Paste")
			(net "M_G_DQ<39>")
		)
		(pad "F41" smd circle
			(at -2.910586 -22.626828)
			(size 0.4318 0.4318)
			(layers "F.Cu" "F.Mask" "F.Paste")
			(net "M_G_DQ<37>")
		)
		(pad "F43" smd circle
			(at -1.193546 -22.626828)
			(size 0.4318 0.4318)
			(layers "F.Cu" "F.Mask" "F.Paste")
			(net "GND")
		)
		(pad "F45" smd circle
			(at 2.052066 -24.426672)
			(size 0.508 0.508)
			(layers "F.Cu" "F.Mask" "F.Paste")
			(net "M_G_CS_N<6>")
		)
		(pad "F47" smd circle
			(at 3.769106 -24.426672)
			(size 0.4318 0.4318)
			(layers "F.Cu" "F.Mask" "F.Paste")
			(net "M_G_CS_N<3>")
		)
		(pad "F49" smd circle
			(at 5.485892 -24.426672)
			(size 0.4318 0.4318)
			(layers "F.Cu" "F.Mask" "F.Paste")
			(net "M_G_CS_N<1>")
		)
		(pad "F51" smd circle
			(at 7.202932 -24.426672)
			(size 0.4318 0.4318)
			(layers "F.Cu" "F.Mask" "F.Paste")
			(net "M_G_MA<14>")
		)
		(pad "F53" smd circle
			(at 8.919972 -24.426672)
			(size 0.4318 0.4318)
			(layers "F.Cu" "F.Mask" "F.Paste")
			(net "M_G_MA<0>")
		)
		(pad "F55" smd circle
			(at 10.637012 -24.426672)
			(size 0.4318 0.4318)
			(layers "F.Cu" "F.Mask" "F.Paste")
			(net "M_G_CLK_DN<0>")
		)
		(pad "F57" smd circle
			(at 12.354052 -24.426672)
			(size 0.4318 0.4318)
			(layers "F.Cu" "F.Mask" "F.Paste")
			(net "M_G_MA<1>")
		)
		(pad "F59" smd circle
			(at 14.071092 -24.426672)
			(size 0.4318 0.4318)
			(layers "F.Cu" "F.Mask" "F.Paste")
			(net "M_G_MA<5>")
		)
		(pad "F61" smd circle
			(at 15.787878 -24.426672)
			(size 0.4318 0.4318)
			(layers "F.Cu" "F.Mask" "F.Paste")
			(net "M_G_MA<9>")
		)
		(pad "F63" smd circle
			(at 17.504918 -24.426672)
			(size 0.4318 0.4318)
			(layers "F.Cu" "F.Mask" "F.Paste")
			(net "M_G_BG<1>")
		)
		(pad "F65" smd circle
			(at 19.221958 -24.426672)
			(size 0.4318 0.4318)
			(layers "F.Cu" "F.Mask" "F.Paste")
			(net "TP_CPU1_RSVD_277")
		)
		(pad "F67" smd custom
			(at 20.938998 -24.426672)
			(size 0.10795 0.10795)
			(layers "F.Cu" "F.Mask" "F.Paste")
			(net "GND")
			(options
				(clearance outline)
				(anchor circle)
			)
			(primitives
				(gr_poly
					(pts
						(arc
							(start 0.2159 -0.0381)
							(mid 0 -0.254)
							(end -0.2159 -0.0381)
						)
						(arc
							(start -0.2159 0.0381)
							(mid 0 0.254)
							(end 0.2159 0.0381)
						)
					)
					(width 0)
					(fill yes)
				)
			)
		)
	)
)
